(kicad_pcb
	(version 20211014)
	(generator pcbnew)
	(general
    (thickness 1.6)
  )
	(paper "A4")
	(title_block
    (title "SA800U (Snapdragon 845) Baseboard")
    (date "2023-10-19")
    (rev "1.0.3")
    (company "Antmicro Ltd.")
    (comment 1 "www.antmicro.com")
		(comment 9 "footprints 402-407 of 589")
	)
	(layers
    (0 "F.Cu" signal)
    (1 "In1.Cu" power)
    (2 "In2.Cu" signal)
    (3 "In3.Cu" signal)
    (4 "In4.Cu" power)
    (31 "B.Cu" signal)
    (32 "B.Adhes" user "B.Adhesive")
    (33 "F.Adhes" user "F.Adhesive")
    (34 "B.Paste" user)
    (35 "F.Paste" user)
    (36 "B.SilkS" user "B.Silkscreen")
    (37 "F.SilkS" user "F.Silkscreen")
    (38 "B.Mask" user)
    (39 "F.Mask" user)
    (40 "Dwgs.User" user "User.Drawings")
    (41 "Cmts.User" user "User.Comments")
    (42 "Eco1.User" user "User.Eco1")
    (43 "Eco2.User" user "User.Eco2")
    (44 "Edge.Cuts" user)
    (45 "Margin" user)
    (46 "B.CrtYd" user "B.Courtyard")
    (47 "F.CrtYd" user "F.Courtyard")
    (48 "B.Fab" user)
    (49 "F.Fab" user)
  )
	(footprint "sa800u-baseboard-hw-footprints:C_0402_1005Metric" (layer "B.Cu")
    (tedit 616D63CF)
    (at 104 138.1 -90)
    (descr "Capacitor SMD 0402")
    (tags "capacitor SMD 0402")
    (property "Author" "Antmicro")
    (property "Dielectric" "X5R")
    (property "License" "Apache-2.0")
    (property "MPN" "GRM155R61H104KE14D")
    (property "Manufacturer" "Murata")
    (property "Sheetfile" "usb-c-interface.kicad_sch")
    (property "Sheetname" "USB-C Interface ")
    (property "Val" "100n")
    (property "Voltage" "50V")
    (attr smd)
    (fp_text reference "C80" (at -3.07 -0.34 90) (layer "B.SilkS")
      (effects (font (size 0.7 0.7) (thickness 0.15)) (justify left bottom mirror))
    )
    (fp_text value "C_100n_0402" (at 0 -1.4 90) (layer "B.Fab")
      (effects (font (size 0.7 0.7) (thickness 0.15)) (justify left bottom mirror))
    )
    (fp_text user "${REFERENCE}" (at -0.932 -3.168 90) (layer "B.Fab") hide
      (effects (font (size 0.7 0.7) (thickness 0.15)) (justify left bottom mirror))
    )
    (fp_text user "License: Apache-2.0" (at -0.932 -5.17 90) (layer "B.Fab") hide
      (effects (font (size 0.7 0.7) (thickness 0.15)) (justify left bottom mirror))
    )
    (fp_text user "Author: Antmicro" (at -0.932 -4.17 90) (layer "B.Fab") hide
      (effects (font (size 0.7 0.7) (thickness 0.15)) (justify left bottom mirror))
    )
    (fp_rect (start -0.94 0.47) (end 0.94 -0.47) (layer "B.CrtYd") (width 0.05) (fill none))
    (fp_rect (start -0.499 0.249) (end 0.499 -0.249) (layer "B.Fab") (width 0.15) (fill none))
    (pad "1" smd roundrect (at -0.484 0 270) (size 0.59 0.64) (layers "B.Cu" "B.Paste" "B.Mask") (roundrect_rratio 0.25)
      (net 68 "USB1_SS_RX1_P") (pintype "passive"))
    (pad "2" smd roundrect (at 0.484 0 270) (size 0.59 0.64) (layers "B.Cu" "B.Paste" "B.Mask") (roundrect_rratio 0.25)
      (net 305 "/USB-C Interface /USB1C_RX1_C_P") (pintype "passive"))
  )
	(footprint "sa800u-baseboard-hw-footprints:C_0402_1005Metric" (layer "B.Cu")
    (tedit 616D63CF)
    (at 103 138.1 -90)
    (descr "Capacitor SMD 0402")
    (tags "capacitor SMD 0402")
    (property "Author" "Antmicro")
    (property "Dielectric" "X5R")
    (property "License" "Apache-2.0")
    (property "MPN" "GRM155R61H104KE14D")
    (property "Manufacturer" "Murata")
    (property "Sheetfile" "usb-c-interface.kicad_sch")
    (property "Sheetname" "USB-C Interface ")
    (property "Val" "100n")
    (property "Voltage" "50V")
    (attr smd)
    (fp_text reference "C84" (at -3.07 -0.34 90) (layer "B.SilkS")
      (effects (font (size 0.7 0.7) (thickness 0.15)) (justify left bottom mirror))
    )
    (fp_text value "C_100n_0402" (at 0 -1.4 90) (layer "B.Fab")
      (effects (font (size 0.7 0.7) (thickness 0.15)) (justify left bottom mirror))
    )
    (fp_text user "Author: Antmicro" (at -0.932 -4.17 90) (layer "B.Fab") hide
      (effects (font (size 0.7 0.7) (thickness 0.15)) (justify left bottom mirror))
    )
    (fp_text user "${REFERENCE}" (at -0.932 -3.168 90) (layer "B.Fab") hide
      (effects (font (size 0.7 0.7) (thickness 0.15)) (justify left bottom mirror))
    )
    (fp_text user "License: Apache-2.0" (at -0.932 -5.17 90) (layer "B.Fab") hide
      (effects (font (size 0.7 0.7) (thickness 0.15)) (justify left bottom mirror))
    )
    (fp_rect (start -0.94 0.47) (end 0.94 -0.47) (layer "B.CrtYd") (width 0.05) (fill none))
    (fp_rect (start -0.499 0.249) (end 0.499 -0.249) (layer "B.Fab") (width 0.15) (fill none))
    (pad "1" smd roundrect (at -0.484 0 270) (size 0.59 0.64) (layers "B.Cu" "B.Paste" "B.Mask") (roundrect_rratio 0.25)
      (net 67 "USB1_SS_RX1_N") (pintype "passive"))
    (pad "2" smd roundrect (at 0.484 0 270) (size 0.59 0.64) (layers "B.Cu" "B.Paste" "B.Mask") (roundrect_rratio 0.25)
      (net 304 "/USB-C Interface /USB1C_RX1_C_N") (pintype "passive"))
  )
	(footprint "sa800u-baseboard-hw-footprints:C_0402_1005Metric" (layer "B.Cu")
    (tedit 616D63CF)
    (at 106 138.1 90)
    (descr "Capacitor SMD 0402")
    (tags "capacitor SMD 0402")
    (property "Author" "Antmicro")
    (property "Dielectric" "X5R")
    (property "License" "Apache-2.0")
    (property "MPN" "GRM155R61H104KE14D")
    (property "Manufacturer" "Murata")
    (property "Sheetfile" "usb-c-interface.kicad_sch")
    (property "Sheetname" "USB-C Interface ")
    (property "Val" "100n")
    (property "Voltage" "50V")
    (attr smd)
    (fp_text reference "C88" (at 3.04 0.38 270) (layer "B.SilkS")
      (effects (font (size 0.7 0.7) (thickness 0.15)) (justify left bottom mirror))
    )
    (fp_text value "C_100n_0402" (at 0 -1.4 270) (layer "B.Fab")
      (effects (font (size 0.7 0.7) (thickness 0.15)) (justify left bottom mirror))
    )
    (fp_text user "License: Apache-2.0" (at -0.932 -5.17 270) (layer "B.Fab") hide
      (effects (font (size 0.7 0.7) (thickness 0.15)) (justify left bottom mirror))
    )
    (fp_text user "Author: Antmicro" (at -0.932 -4.17 270) (layer "B.Fab") hide
      (effects (font (size 0.7 0.7) (thickness 0.15)) (justify left bottom mirror))
    )
    (fp_text user "${REFERENCE}" (at -0.932 -3.168 270) (layer "B.Fab") hide
      (effects (font (size 0.7 0.7) (thickness 0.15)) (justify left bottom mirror))
    )
    (fp_rect (start -0.94 0.47) (end 0.94 -0.47) (layer "B.CrtYd") (width 0.05) (fill none))
    (fp_rect (start -0.499 0.249) (end 0.499 -0.249) (layer "B.Fab") (width 0.15) (fill none))
    (pad "1" smd roundrect (at -0.484 0 90) (size 0.59 0.64) (layers "B.Cu" "B.Paste" "B.Mask") (roundrect_rratio 0.25)
      (net 307 "/USB-C Interface /USB1C_TX1_C_P") (pintype "passive"))
    (pad "2" smd roundrect (at 0.484 0 90) (size 0.59 0.64) (layers "B.Cu" "B.Paste" "B.Mask") (roundrect_rratio 0.25)
      (net 72 "USB1_SS_TX1_P") (pintype "passive"))
  )
	(footprint "sa800u-baseboard-hw-footprints:C_0402_1005Metric" (layer "B.Cu")
    (tedit 616D63CF)
    (at 105 138.1 90)
    (descr "Capacitor SMD 0402")
    (tags "capacitor SMD 0402")
    (property "Author" "Antmicro")
    (property "Dielectric" "X5R")
    (property "License" "Apache-2.0")
    (property "MPN" "GRM155R61H104KE14D")
    (property "Manufacturer" "Murata")
    (property "Sheetfile" "usb-c-interface.kicad_sch")
    (property "Sheetname" "USB-C Interface ")
    (property "Val" "100n")
    (property "Voltage" "50V")
    (attr smd)
    (fp_text reference "C93" (at 3.04 0.38 270) (layer "B.SilkS")
      (effects (font (size 0.7 0.7) (thickness 0.15)) (justify left bottom mirror))
    )
    (fp_text value "C_100n_0402" (at 0 -1.4 270) (layer "B.Fab")
      (effects (font (size 0.7 0.7) (thickness 0.15)) (justify left bottom mirror))
    )
    (fp_text user "License: Apache-2.0" (at -0.932 -5.17 270) (layer "B.Fab") hide
      (effects (font (size 0.7 0.7) (thickness 0.15)) (justify left bottom mirror))
    )
    (fp_text user "Author: Antmicro" (at -0.932 -4.17 270) (layer "B.Fab") hide
      (effects (font (size 0.7 0.7) (thickness 0.15)) (justify left bottom mirror))
    )
    (fp_text user "${REFERENCE}" (at -0.932 -3.168 270) (layer "B.Fab") hide
      (effects (font (size 0.7 0.7) (thickness 0.15)) (justify left bottom mirror))
    )
    (fp_rect (start -0.94 0.47) (end 0.94 -0.47) (layer "B.CrtYd") (width 0.05) (fill none))
    (fp_rect (start -0.499 0.249) (end 0.499 -0.249) (layer "B.Fab") (width 0.15) (fill none))
    (pad "1" smd roundrect (at -0.484 0 90) (size 0.59 0.64) (layers "B.Cu" "B.Paste" "B.Mask") (roundrect_rratio 0.25)
      (net 306 "/USB-C Interface /USB1C_TX1_C_N") (pintype "passive"))
    (pad "2" smd roundrect (at 0.484 0 90) (size 0.59 0.64) (layers "B.Cu" "B.Paste" "B.Mask") (roundrect_rratio 0.25)
      (net 71 "USB1_SS_TX1_N") (pintype "passive"))
  )
	(footprint "sa800u-baseboard-hw-footprints:WSON-12-1EP_2x3mm_P0.5mm" (layer "B.Cu")
    (tedit 6215ECFB)
    (at 109.3 143.8 -90)
    (property "Author" "Antmicro")
    (property "License" "Apache-2.0")
    (property "MPN" "TPS25820DSST")
    (property "Manufacturer" "Texas Instruments")
    (property "Sheetfile" "usb-c-interface.kicad_sch")
    (property "Sheetname" "USB-C Interface ")
    (attr smd)
    (fp_text reference "U6" (at 2.21 -0.21 180) (layer "B.SilkS")
      (effects (font (size 0.7 0.7) (thickness 0.15)) (justify left bottom mirror))
    )
    (fp_text value "TPS25820DSST" (at 0 -2.6 90) (layer "B.Fab")
      (effects (font (size 0.7 0.7) (thickness 0.15)) (justify left bottom mirror))
    )
    (fp_text user "Author: Antmicro" (at -1.702 -4.498 90) (layer "B.Fab") hide
      (effects (font (size 0.7 0.7) (thickness 0.15)) (justify left bottom mirror))
    )
    (fp_text user "${REFERENCE}" (at -1.702 -5.698 90) (layer "B.Fab") hide
      (effects (font (size 0.7 0.7) (thickness 0.15)) (justify left bottom mirror))
    )
    (fp_text user "License: Apache-2.0" (at -1.702 -6.898 90) (layer "B.Fab") hide
      (effects (font (size 0.7 0.7) (thickness 0.15)) (justify left bottom mirror))
    )
    (fp_poly (pts
        (xy 0.473 -1.3)
        (xy -0.476 -1.3)
        (xy -0.476 -0.122)
        (xy 0.473 -0.122)
      ) (layer "B.Paste") (width 0.01) (fill solid))
    (fp_poly (pts
        (xy -0.476 1.301)
        (xy 0.473 1.301)
        (xy 0.473 0.125)
        (xy -0.476 0.125)
      ) (layer "B.Paste") (width 0.01) (fill solid))
    (fp_line (start -1 1.5) (end 0.997 1.5) (layer "B.SilkS") (width 0.15))
    (fp_line (start 0.997 -1.499) (end -1 -1.499) (layer "B.SilkS") (width 0.15))
    (fp_circle (center -1.3 1.551) (end -1.249 1.551) (layer "B.SilkS") (width 0.15) (fill solid))
    (fp_rect (start -1.3 1.7) (end 1.3 -1.7) (layer "B.CrtYd") (width 0.05) (fill none))
    (pad "1" smd roundrect (at -0.951 1.25 270) (size 0.5 0.25) (layers "B.Cu" "B.Paste" "B.Mask") (roundrect_rratio 0.2)
      (net 133 "5V_SYS") (pinfunction "IN") (pintype "power_in"))
    (pad "2" smd roundrect (at -0.951 0.75 270) (size 0.5 0.25) (layers "B.Cu" "B.Paste" "B.Mask") (roundrect_rratio 0.2)
      (net 133 "5V_SYS") (pinfunction "IN") (pintype "passive"))
    (pad "3" smd roundrect (at -0.951 0.25 270) (size 0.5 0.25) (layers "B.Cu" "B.Paste" "B.Mask") (roundrect_rratio 0.2)
      (net 1 "GND") (pinfunction "CHG") (pintype "input"))
    (pad "4" smd roundrect (at -0.951 -0.247 270) (size 0.5 0.25) (layers "B.Cu" "B.Paste" "B.Mask") (roundrect_rratio 0.2)
      (net 301 "/USB-C Interface /USB2_EN_5V") (pinfunction "EN") (pintype "input"))
    (pad "5" smd roundrect (at -0.951 -0.747 270) (size 0.5 0.25) (layers "B.Cu" "B.Paste" "B.Mask") (roundrect_rratio 0.2)
      (net 292 "/USB-C Interface /USB2_FAULT_5V") (pinfunction "nFAULT") (pintype "output"))
    (pad "6" smd roundrect (at -0.951 -1.249 270) (size 0.5 0.25) (layers "B.Cu" "B.Paste" "B.Mask") (roundrect_rratio 0.2)
      (net 291 "/USB-C Interface /USB2_SINK_5V") (pinfunction "nSINK") (pintype "output"))
    (pad "7" smd roundrect (at 0.948 -1.249 90) (size 0.5 0.25) (layers "B.Cu" "B.Paste" "B.Mask") (roundrect_rratio 0.2)
      (net 290 "/USB-C Interface /USB2_CC_SELECT") (pinfunction "nPOL") (pintype "output"))
    (pad "8" smd roundrect (at 0.948 -0.747 90) (size 0.5 0.25) (layers "B.Cu" "B.Paste" "B.Mask") (roundrect_rratio 0.2)
      (net 396 "Net-(R59-Pad1)") (pinfunction "REF") (pintype "input"))
    (pad "9" smd roundrect (at 0.948 -0.247 90) (size 0.5 0.25) (layers "B.Cu" "B.Paste" "B.Mask") (roundrect_rratio 0.2)
      (net 265 "/USB-C Interface /USB2_CC1") (pinfunction "CC1") (pintype "bidirectional"))
    (pad "10" smd roundrect (at 0.948 0.25 90) (size 0.5 0.25) (layers "B.Cu" "B.Paste" "B.Mask") (roundrect_rratio 0.2)
      (net 1 "GND") (pinfunction "GND") (pintype "input"))
    (pad "11" smd roundrect (at 0.948 0.75 90) (size 0.5 0.25) (layers "B.Cu" "B.Paste" "B.Mask") (roundrect_rratio 0.2)
      (net 264 "/USB-C Interface /USB2_CC2") (pinfunction "CC2") (pintype "bidirectional"))
    (pad "12" smd roundrect (at 0.948 1.25 90) (size 0.5 0.25) (layers "B.Cu" "B.Paste" "B.Mask") (roundrect_rratio 0.2)
      (net 210 "/USB-C Interface /USB2_5V") (pinfunction "OUT") (pintype "power_out"))
    (pad "13" smd roundrect (at 0 0 270) (size 1 2.65) (layers "B.Cu" "B.Paste" "B.Mask") (roundrect_rratio 0.05)
      (net 1 "GND") (pinfunction "GND") (pintype "passive") (solder_paste_margin_ratio -0.5))
  )
	(footprint "sa800u-baseboard-hw-footprints:DHVQFN-20-1EP_2.5x4.5_P0.5mm" (layer "B.Cu")
    (tedit 6215E186)
    (at 115.75 133.5 -90)
    (property "Author" "Antmicro")
    (property "License" "Apache-2.0")
    (property "MPN" "CBTL02043ABQ,115")
    (property "Manufacturer" "Nexperia")
    (property "Sheetfile" "usb-c-interface.kicad_sch")
    (property "Sheetname" "USB-C Interface ")
    (attr smd)
    (fp_text reference "U9" (at -2.19 2.45 90) (layer "B.SilkS")
      (effects (font (size 0.7 0.7) (thickness 0.15)) (justify left bottom mirror))
    )
    (fp_text value "CBTL02043ABQ,115" (at 0 -3.85 90) (layer "B.Fab")
      (effects (font (size 0.7 0.7) (thickness 0.15)) (justify left bottom mirror))
    )
    (fp_text user "Author: Antmicro" (at -1.95 -5.849 90) (layer "B.Fab") hide
      (effects (font (size 0.7 0.7) (thickness 0.15)) (justify left bottom mirror))
    )
    (fp_text user "License: Apache-2.0" (at -1.95 -7.049 90) (layer "B.Fab") hide
      (effects (font (size 0.7 0.7) (thickness 0.15)) (justify left bottom mirror))
    )
    (fp_text user "${REFERENCE}" (at -1.95 -8.249 90) (layer "B.Fab") hide
      (effects (font (size 0.7 0.7) (thickness 0.15)) (justify left bottom mirror))
    )
    (fp_poly (pts
        (xy -0.203 -0.2)
        (xy 0.2 -0.2)
        (xy 0.2 -0.847)
        (xy -0.203 -0.847)
      ) (layer "B.Paste") (width 0.01) (fill solid))
    (fp_poly (pts
        (xy 0.2 0.203)
        (xy -0.203 0.203)
        (xy -0.203 0.85)
        (xy 0.2 0.85)
      ) (layer "B.Paste") (width 0.01) (fill solid))
    (fp_line (start -1.25 2.25) (end -1.25 2) (layer "B.SilkS") (width 0.15))
    (fp_line (start 1.249 -2.249) (end 0.5 -2.249) (layer "B.SilkS") (width 0.15))
    (fp_line (start 1.249 -2.249) (end 1.25 -2) (layer "B.SilkS") (width 0.15))
    (fp_line (start 1.249 2.25) (end 1.25 2) (layer "B.SilkS") (width 0.15))
    (fp_line (start -1.25 -2.249) (end -1.25 -2) (layer "B.SilkS") (width 0.15))
    (fp_line (start 1.249 2.25) (end 0.5 2.25) (layer "B.SilkS") (width 0.15))
    (fp_line (start -1.25 2.25) (end -0.5 2.25) (layer "B.SilkS") (width 0.15))
    (fp_line (start -1.25 -2.249) (end -0.5 -2.249) (layer "B.SilkS") (width 0.15))
    (fp_circle (center -0.6 2.5) (end -0.551 2.5) (layer "B.SilkS") (width 0.15) (fill solid))
    (fp_rect (start -1.8 2.8) (end 1.8 -2.7) (layer "B.CrtYd") (width 0.05) (fill none))
    (pad "1" smd rect (at -0.248 2.261 270) (size 0.29 0.8) (layers "B.Cu" "B.Paste" "B.Mask")
      (net 131 "3V3_SYS") (pinfunction "VDD") (pintype "power_in") (solder_paste_margin -0.025))
    (pad "2" smd rect (at -1.26 1.75 180) (size 0.29 0.8) (layers "B.Cu" "B.Paste" "B.Mask")
      (net 1 "GND") (pinfunction "XSD") (pintype "input") (solder_paste_margin -0.025))
    (pad "3" smd rect (at -1.26 1.25 180) (size 0.29 0.8) (layers "B.Cu" "B.Paste" "B.Mask")
      (net 105 "USB2_SS_RX_P") (pinfunction "A0_P") (pintype "bidirectional") (solder_paste_margin -0.025))
    (pad "4" smd rect (at -1.26 0.75 180) (size 0.29 0.8) (layers "B.Cu" "B.Paste" "B.Mask")
      (net 104 "USB2_SS_RX_N") (pinfunction "A0_N") (pintype "bidirectional") (solder_paste_margin -0.025))
    (pad "5" smd rect (at -1.26 0.25 180) (size 0.29 0.8) (layers "B.Cu" "B.Paste" "B.Mask")
      (net 1 "GND") (pinfunction "GND") (pintype "passive") (solder_paste_margin -0.025))
    (pad "6" smd rect (at -1.26 -0.247 180) (size 0.29 0.8) (layers "B.Cu" "B.Paste" "B.Mask")
      (net 131 "3V3_SYS") (pinfunction "VDD") (pintype "passive") (solder_paste_margin -0.025))
    (pad "7" smd rect (at -1.26 -0.747 180) (size 0.29 0.8) (layers "B.Cu" "B.Paste" "B.Mask")
      (net 103 "USB2_SS_TX_P") (pinfunction "A1_P") (pintype "bidirectional") (solder_paste_margin -0.025))
    (pad "8" smd rect (at -1.26 -1.249 180) (size 0.29 0.8) (layers "B.Cu" "B.Paste" "B.Mask")
      (net 102 "USB2_SS_TX_N") (pinfunction "A1_N") (pintype "bidirectional") (solder_paste_margin -0.025))
    (pad "9" smd rect (at -1.26 -1.749 180) (size 0.29 0.8) (layers "B.Cu" "B.Paste" "B.Mask")
      (net 290 "/USB-C Interface /USB2_CC_SELECT") (pinfunction "SEL") (pintype "input") (solder_paste_margin -0.025))
    (pad "10" smd rect (at -0.248 -2.15 270) (size 0.29 0.8) (layers "B.Cu" "B.Paste" "B.Mask")
      (net 131 "3V3_SYS") (pinfunction "VDD") (pintype "passive") (solder_paste_margin -0.025))
    (pad "11" smd rect (at 0.249 -2.15 270) (size 0.29 0.8) (layers "B.Cu" "B.Paste" "B.Mask")
      (net 1 "GND") (pinfunction "GND") (pintype "power_in") (solder_paste_margin -0.025))
    (pad "12" smd rect (at 1.259 -1.749 180) (size 0.29 0.8) (layers "B.Cu" "B.Paste" "B.Mask")
      (net 225 "/USB-C Interface /USB2C_TX2_N") (pinfunction "C1_N") (pintype "bidirectional") (solder_paste_margin -0.025))
    (pad "13" smd rect (at 1.259 -1.249 180) (size 0.29 0.8) (layers "B.Cu" "B.Paste" "B.Mask")
      (net 221 "/USB-C Interface /USB2C_TX2_P") (pinfunction "C1_P") (pintype "bidirectional") (solder_paste_margin -0.025))
    (pad "14" smd rect (at 1.259 -0.747 180) (size 0.29 0.8) (layers "B.Cu" "B.Paste" "B.Mask")
      (net 218 "/USB-C Interface /USB2C_RX2_N") (pinfunction "C0_N") (pintype "bidirectional") (solder_paste_margin -0.025))
    (pad "15" smd rect (at 1.259 -0.247 180) (size 0.29 0.8) (layers "B.Cu" "B.Paste" "B.Mask")
      (net 214 "/USB-C Interface /USB2C_RX2_P") (pinfunction "C0_P") (pintype "bidirectional") (solder_paste_margin -0.025))
    (pad "16" smd rect (at 1.259 0.25 180) (size 0.29 0.8) (layers "B.Cu" "B.Paste" "B.Mask")
      (net 212 "/USB-C Interface /USB2C_TX1_N") (pinfunction "B1_N") (pintype "bidirectional") (solder_paste_margin -0.025))
    (pad "17" smd rect (at 1.259 0.75 180) (size 0.29 0.8) (layers "B.Cu" "B.Paste" "B.Mask")
      (net 216 "/USB-C Interface /USB2C_TX1_P") (pinfunction "B1_P") (pintype "bidirectional") (solder_paste_margin -0.025))
    (pad "18" smd rect (at 1.259 1.25 180) (size 0.29 0.8) (layers "B.Cu" "B.Paste" "B.Mask")
      (net 219 "/USB-C Interface /USB2C_RX1_N") (pinfunction "B0_N") (pintype "bidirectional") (solder_paste_margin -0.025))
    (pad "19" smd rect (at 1.259 1.75 180) (size 0.29 0.8) (layers "B.Cu" "B.Paste" "B.Mask")
      (net 223 "/USB-C Interface /USB2C_RX1_P") (pinfunction "B0_P") (pintype "bidirectional") (solder_paste_margin -0.025))
    (pad "20" smd rect (at 0.249 2.261 270) (size 0.29 0.8) (layers "B.Cu" "B.Paste" "B.Mask")
      (net 1 "GND") (pinfunction "GND") (pintype "passive") (solder_paste_margin -0.025))
    (pad "21" smd rect (at 0 0 90) (size 0.9 2.9) (layers "B.Cu" "B.Paste" "B.Mask")
      (net 1 "GND") (pinfunction "GND") (pintype "passive") (solder_paste_margin_ratio -0.5))
  )
)
